# BASEBOARD_FAB2 (Tioga Pass) — schematic netlist excerpt (pin names and nets, part order shuffled) for the footprints in the layout excerpt that follows; sources: Cadence DE-HDL packaged netlist, KiCad conversion of Wiwynn_Tioga_Pass_MB.brd

R6F10  RES  0.0 5% EMPTY  pkg 0402  page 104 : A = CLK_322M_156M_CPU0_OSC_VRM_DN ; B = CLK_322M_OSC_CPU0_RC_DN
C5D61  CAP_A  22.0UF 4V 20% X6S  pkg 0603V  page 217 : A = PVDDQ_ABC ; B = GND
C4E17  CAP  0.220UF 16V 10% X7R  pkg 0402  page 202 : A = VR_PVCCIN_CPU0_PH1_BOOT ; B = VR_PVCCIN_CPU0_PH1_PHASE

(kicad_pcb
	(version 20260206)
	(generator "pcbnew")
	(generator_version "10.0")
	(general
		(thickness 1.6)
		(legacy_teardrops no)
	)
	(paper "A4")
	(title_block
		(title "Wiwynn_Tioga_Pass_MB.brd")
		(comment 1 "Tioga Pass / footprints 1558-1560 of 4770")
	)
	(layers
		(0 "F.Cu" signal "TOP")
		(4 "In1.Cu" signal "L2GND")
		(6 "In2.Cu" signal "L3")
		(8 "In3.Cu" signal "L4GND")
		(10 "In4.Cu" signal "L5")
		(12 "In5.Cu" signal "L6GND")
		(14 "In6.Cu" signal "L7VCC")
		(16 "In7.Cu" signal "L8VCC")
		(18 "In8.Cu" signal "L9GND")
		(20 "In9.Cu" signal "L10")
		(22 "In10.Cu" signal "L11GND")
		(24 "In11.Cu" signal "L12")
		(26 "In12.Cu" signal "L13GND")
		(2 "B.Cu" signal "BOTTOM")
		(9 "F.Adhes" user "F.Adhesive")
		(11 "B.Adhes" user "B.Adhesive")
		(13 "F.Paste" user "Package Geometry/Pastemask Top")
		(15 "B.Paste" user "Package Geometry/Pastemask Bottom")
		(5 "F.SilkS" user "Ref Des/Silkscreen Top")
		(7 "B.SilkS" user "Ref Des/Silkscreen Bottom")
		(1 "F.Mask" user "Board Geometry/Soldermask Top")
		(3 "B.Mask" user "Board Geometry/Soldermask Bottom")
		(17 "Dwgs.User" user "User.Drawings")
		(19 "Cmts.User" user "User.Comments")
		(21 "Eco1.User" user "User.Eco1")
		(23 "Eco2.User" user "User.Eco2")
		(25 "Edge.Cuts" user "Board Geometry/Outline")
		(27 "Margin" user)
		(31 "F.CrtYd" user "Package Geometry/Place Bound Top")
		(29 "B.CrtYd" user "Package Geometry/Place Bound Bottom")
		(35 "F.Fab" user "Ref Des/Assembly Top")
		(33 "B.Fab" user "Ref Des/Assembly Bottom")
	)
	(footprint ""
		(layer "F.Cu")
		(at 318.8716 -30.585918 -90)
		(property "Reference" "R6F10"
			(at 0 0 270)
			(layer "F.SilkS")
			(hide yes)
			(effects
				(font
					(size 1.27 1.27)
				)
			)
		)
		(property "Value" ""
			(at 0 0 270)
			(layer "F.Fab")
			(effects
				(font
					(size 1.27 1.27)
				)
			)
		)
		(duplicate_pad_numbers_are_jumpers no)
		(fp_poly
			(pts
				(xy -0.2794 -0.1016) (xy 0.2794 -0.1016) (xy 0.2794 0.9906) (xy -0.2794 0.9906)
			)
			(stroke
				(width 0)
				(type default)
			)
			(fill no)
			(layer "F.CrtYd")
		)
		(fp_line
			(start -0.2794 0.9906)
			(end 0.2794 0.9906)
			(stroke
				(width 0.1)
				(type default)
			)
			(layer "F.Fab")
		)
		(fp_line
			(start 0.2794 0.9906)
			(end 0.2794 -0.1016)
			(stroke
				(width 0.1)
				(type default)
			)
			(layer "F.Fab")
		)
		(fp_line
			(start -0.2794 -0.1016)
			(end -0.2794 0.9906)
			(stroke
				(width 0.1)
				(type default)
			)
			(layer "F.Fab")
		)
		(fp_line
			(start 0.2794 -0.1016)
			(end -0.2794 -0.1016)
			(stroke
				(width 0.1)
				(type default)
			)
			(layer "F.Fab")
		)
		(pad "1" smd rect
			(at 0 0 270)
			(size 0.508 0.508)
			(layers "F.Cu" "F.Mask" "F.Paste")
			(net "CLK_322M_156M_CPU0_OSC_VRM_DN")
		)
		(pad "2" smd rect
			(at 0 0.889 270)
			(size 0.508 0.508)
			(layers "F.Cu" "F.Mask" "F.Paste")
			(net "CLK_322M_OSC_CPU0_RC_DN")
		)
		(zone
			(layer "F.Cu")
			(hatch none 0.5)
			(connect_pads
				(clearance 0)
			)
			(min_thickness 0.25)
			(keepout
				(tracks not_allowed)
				(vias allowed)
				(pads allowed)
				(copperpour not_allowed)
				(footprints allowed)
			)
			(placement
				(enabled no)
				(sheetname "")
			)
			(fill
				(thermal_gap 0.5)
				(thermal_bridge_width 0.5)
				(island_removal_mode 0)
			)
			(polygon
				(pts
					(xy 318.2366 -30.839918) (xy 318.2366 -30.331918) (xy 318.6176 -30.331918) (xy 318.6176 -30.839918)
				)
			)
		)
		(zone
			(layer "F.Cu")
			(hatch none 0.5)
			(connect_pads
				(clearance 0)
			)
			(min_thickness 0.25)
			(keepout
				(tracks allowed)
				(vias not_allowed)
				(pads allowed)
				(copperpour not_allowed)
				(footprints allowed)
			)
			(placement
				(enabled no)
				(sheetname "")
			)
			(fill
				(thermal_gap 0.5)
				(thermal_bridge_width 0.5)
				(island_removal_mode 0)
			)
			(polygon
				(pts
					(xy 318.6176 -30.839918) (xy 318.6176 -30.331918) (xy 318.2366 -30.331918) (xy 318.2366 -30.839918)
				)
			)
		)
	)
	(footprint ""
		(layer "F.Cu")
		(at 193.8782 -58.928 90)
		(property "Reference" "C4E17"
			(at 0 0 90)
			(layer "F.SilkS")
			(hide yes)
			(effects
				(font
					(size 1.27 1.27)
				)
			)
		)
		(property "Value" ""
			(at 0 0 90)
			(layer "F.Fab")
			(effects
				(font
					(size 1.27 1.27)
				)
			)
		)
		(duplicate_pad_numbers_are_jumpers no)
		(fp_rect
			(start -0.3048 0.9906)
			(end 0.3048 -0.1016)
			(stroke
				(width 0)
				(type default)
			)
			(fill no)
			(layer "F.CrtYd")
		)
		(fp_line
			(start 0.3048 -0.1016)
			(end -0.3048 -0.1016)
			(stroke
				(width 0.1)
				(type default)
			)
			(layer "F.Fab")
		)
		(fp_line
			(start -0.3048 -0.1016)
			(end -0.3048 0.9906)
			(stroke
				(width 0.1)
				(type default)
			)
			(layer "F.Fab")
		)
		(fp_line
			(start 0.3048 0.9906)
			(end 0.3048 -0.1016)
			(stroke
				(width 0.1)
				(type default)
			)
			(layer "F.Fab")
		)
		(fp_line
			(start -0.3048 0.9906)
			(end 0.3048 0.9906)
			(stroke
				(width 0.1)
				(type default)
			)
			(layer "F.Fab")
		)
		(pad "1" smd rect
			(at 0 0 90)
			(size 0.508 0.508)
			(layers "F.Cu" "F.Mask" "F.Paste")
			(net "VR_PVCCIN_CPU0_PH1_BOOT")
		)
		(pad "2" smd rect
			(at 0 0.889 90)
			(size 0.508 0.508)
			(layers "F.Cu" "F.Mask" "F.Paste")
			(net "VR_PVCCIN_CPU0_PH1_PHASE")
		)
		(zone
			(layer "F.Cu")
			(hatch none 0.5)
			(connect_pads
				(clearance 0)
			)
			(min_thickness 0.25)
			(keepout
				(tracks allowed)
				(vias not_allowed)
				(pads allowed)
				(copperpour not_allowed)
				(footprints allowed)
			)
			(placement
				(enabled no)
				(sheetname "")
			)
			(fill
				(thermal_gap 0.5)
				(thermal_bridge_width 0.5)
				(island_removal_mode 0)
			)
			(polygon
				(pts
					(xy 194.5132 -58.674) (xy 194.5132 -59.182) (xy 194.1322 -59.182) (xy 194.1322 -58.674)
				)
			)
		)
		(zone
			(layer "F.Cu")
			(hatch none 0.5)
			(connect_pads
				(clearance 0)
			)
			(min_thickness 0.25)
			(keepout
				(tracks not_allowed)
				(vias allowed)
				(pads allowed)
				(copperpour not_allowed)
				(footprints allowed)
			)
			(placement
				(enabled no)
				(sheetname "")
			)
			(fill
				(thermal_gap 0.5)
				(thermal_bridge_width 0.5)
				(island_removal_mode 0)
			)
			(polygon
				(pts
					(xy 194.5132 -58.674) (xy 194.5132 -59.182) (xy 194.1322 -59.182) (xy 194.1322 -58.674)
				)
			)
		)
	)
	(footprint ""
		(layer "F.Cu")
		(at 272.134838 -68.365116 180)
		(property "Reference" "C5D61"
			(at 0 0 180)
			(layer "F.SilkS")
			(hide yes)
			(effects
				(font
					(size 1.27 1.27)
				)
			)
		)
		(property "Value" ""
			(at 0 0 180)
			(layer "F.Fab")
			(effects
				(font
					(size 1.27 1.27)
				)
			)
		)
		(duplicate_pad_numbers_are_jumpers no)
		(fp_poly
			(pts
				(xy -0.4953 -0.2032) (xy 0.4953 -0.2032) (xy 0.4953 1.6002) (xy -0.4953 1.6002)
			)
			(stroke
				(width 0)
				(type default)
			)
			(fill no)
			(layer "F.CrtYd")
		)
		(fp_line
			(start 0.4953 1.6002)
			(end -0.4953 1.6002)
			(stroke
				(width 0.1)
				(type default)
			)
			(layer "F.Fab")
		)
		(fp_line
			(start 0.4953 -0.2032)
			(end 0.4953 1.6002)
			(stroke
				(width 0.1)
				(type default)
			)
			(layer "F.Fab")
		)
		(fp_line
			(start -0.4953 1.6002)
			(end -0.4953 -0.2032)
			(stroke
				(width 0.1)
				(type default)
			)
			(layer "F.Fab")
		)
		(fp_line
			(start -0.4953 -0.2032)
			(end 0.4953 -0.2032)
			(stroke
				(width 0.1)
				(type default)
			)
			(layer "F.Fab")
		)
		(pad "1" smd rect
			(at 0 0 180)
			(size 0.762 0.889)
			(layers "F.Cu" "F.Mask" "F.Paste")
			(net "PVDDQ_ABC")
		)
		(pad "2" smd rect
			(at 0 1.397 180)
			(size 0.762 0.889)
			(layers "F.Cu" "F.Mask" "F.Paste")
			(net "GND")
		)
		(zone
			(layer "F.Cu")
			(hatch none 0.5)
			(connect_pads
				(clearance 0)
			)
			(min_thickness 0.25)
			(keepout
				(tracks not_allowed)
				(vias allowed)
				(pads allowed)
				(copperpour not_allowed)
				(footprints allowed)
			)
			(placement
				(enabled no)
				(sheetname "")
			)
			(fill
				(thermal_gap 0.5)
				(thermal_bridge_width 0.5)
				(island_removal_mode 0)
			)
			(polygon
				(pts
					(xy 272.515838 -68.809616) (xy 271.753838 -68.809616) (xy 271.753838 -69.317616) (xy 272.515838 -69.317616)
				)
			)
		)
	)
)
